# S9S_MB_2U (Grand Teton) — schematic parts with pin connectivity, parts 1603–1603 of 6093; source: Cadence DE-HDL packaged netlist (pstxprt.dat, pstxnet.dat, pstchip.dat)

J10  SCONN288_ADR50017P087CC  SCONN288_ADR50017-P087CC IO  pkg DDR288S_1-1VXB  page 91
  1  VIN_BULK0  POWER  = P12V_S3_AUX_CPU0_NVDIMM
  2  RFU0  TRI  = TP_CHE_CPU0_DIMM2_FRU_0
  3  VIN_MGMT  POWER  = P3V3_AUX
  4  HSCL  IN  = I3C_SPD_DDREFGH_CPU0_LVC1_SCL_1
  5  HSDA  BI  = I3C_SPD_DDREFGH_CPU0_LVC1_SDA
  6  VSS0  POWER  = GND
  7  DQ0_A  BI  = M_E_CPU0_SA_DQ<0>
  8  VSS1  POWER  = GND
  9  DQ1_A  BI  = M_E_CPU0_SA_DQ<1>
  10  VSS2  POWER  = GND
  11  DQS0_A_T  BI  = M_E_CPU0_SA_DQS_DP<0>
  12  DQS0_A_C  BI  = M_E_CPU0_SA_DQS_DN<0>
  13  VSS3  POWER  = GND
  14  DQ4_A  BI  = M_E_CPU0_SA_DQ<4>
  15  VSS4  POWER  = GND
  16  DQ5_A  BI  = M_E_CPU0_SA_DQ<5>
  17  VSS5  POWER  = GND
  18  DQ8_A  BI  = M_E_CPU0_SA_DQ<8>
  19  VSS6  POWER  = GND
  20  DQ9_A  BI  = M_E_CPU0_SA_DQ<9>
  21  VSS7  POWER  = GND
  22  DQS1_A_T  BI  = M_E_CPU0_SA_DQS_DP<1>
  23  DQS1_A_C  BI  = M_E_CPU0_SA_DQS_DN<1>
  24  VSS8  POWER  = GND
  25  DQ12_A  BI  = M_E_CPU0_SA_DQ<12>
  26  VSS9  POWER  = GND
  27  DQ13_A  BI  = M_E_CPU0_SA_DQ<13>
  28  VSS10  POWER  = GND
  29  DQ16_A  BI  = M_E_CPU0_SA_DQ<16>
  30  VSS11  POWER  = GND
  31  DQ17_A  BI  = M_E_CPU0_SA_DQ<17>
  32  VSS12  POWER  = GND
  33  DQS2_A_T  BI  = M_E_CPU0_SA_DQS_DP<2>
  34  DQS2_A_C  BI  = M_E_CPU0_SA_DQS_DN<2>
  35  VSS13  POWER  = GND
  36  DQ20_A  BI  = M_E_CPU0_SA_DQ<20>
  37  VSS14  POWER  = GND
  38  DQ21_A  BI  = M_E_CPU0_SA_DQ<21>
  39  VSS15  POWER  = GND
  40  DQ24_A  BI  = M_E_CPU0_SA_DQ<24>
  41  VSS16  POWER  = GND
  42  DQ25_A  BI  = M_E_CPU0_SA_DQ<25>
  43  VSS17  POWER  = GND
  44  DQS3_A_T  BI  = M_E_CPU0_SA_DQS_DP<3>
  45  DQS3_A_C  BI  = M_E_CPU0_SA_DQS_DN<3>
  46  VSS18  POWER  = GND
  47  DQ28_A  BI  = M_E_CPU0_SA_DQ<28>
  48  VSS19  POWER  = GND
  49  DQ29_A  BI  = M_E_CPU0_SA_DQ<29>
  50  VSS20  POWER  = GND
  51  CB0_A  BI  = M_E_CPU0_SA_CB<0>
  52  VSS21  POWER  = GND
  53  CB1_A  BI  = M_E_CPU0_SA_CB<1>
  54  VSS22  POWER  = GND
  55  DQS4_A_T  BI  = M_E_CPU0_SA_DQS_DP<4>
  56  DQS4_A_C  BI  = M_E_CPU0_SA_DQS_DN<4>
  57  VSS23  POWER  = GND
  58  CB4_A  BI  = M_E_CPU0_SA_CB<4>
  59  VSS24  POWER  = GND
  60  CB5_A  BI  = M_E_CPU0_SA_CB<5>
  61  VSS25  POWER  = GND
  62  ALERT_N  OUT  = M_E_CPU0_ALERT_N
  63  VSS26  POWER  = GND
  64  CS0_A_N  IN  = M_E_CPU0_SA_CS_N<2>
  65  VSS27  POWER  = GND
  66  CA0_A  IN  = M_E_CPU0_SA_CA<0>
  67  VSS28  POWER  = GND
  68  CA2_A  IN  = M_E_CPU0_SA_CA<2>
  69  VSS29  POWER  = GND
  70  CA4_A  IN  = M_E_CPU0_SA_CA<4>
  71  VSS30  POWER  = GND
  72  CA6_A  IN  = M_E_CPU0_SA_CA<6>
  73  VSS31  POWER  = GND
  74  PAR_A  IN  = M_E_CPU0_SA_PAR
  75  VSS32  POWER  = GND
  76  CA0_B  IN  = M_E_CPU0_SB_CA<0>
  77  VSS33  POWER  = GND
  78  CA2_B  IN  = M_E_CPU0_SB_CA<2>
  79  VSS34  POWER  = GND
  80  CA4_B  IN  = M_E_CPU0_SB_CA<4>
  81  VSS35  POWER  = GND
  82  CA6_B  IN  = M_E_CPU0_SB_CA<6>
  83  VSS36  POWER  = GND
  84  CS0_B_N  IN  = M_E_CPU0_SB_CS_N<2>
  85  VSS37  POWER  = GND
  86  \lbd||rsp_a_n\  OUT  = M_E_CPU0_SA_RSP<1>
  87  \lbs||rsp_b_n\  OUT  = M_E_CPU0_SB_RSP<1>
  88  VSS38  POWER  = GND
  89  CB4_B  BI  = M_E_CPU0_SB_CB<4>
  90  VSS39  POWER  = GND
  91  CB5_B  BI  = M_E_CPU0_SB_CB<5>
  92  VSS40  POWER  = GND
  93  \dqs9_b_t||tdqs9_b_t||dbi4_b_n\  BI  = M_E_CPU0_SB_DQS_DP<9>
  94  \dqs9_b_c||tdqs9_b_c\  BI  = M_E_CPU0_SB_DQS_DN<9>
  95  VSS41  POWER  = GND
  96  CB0_B  BI  = M_E_CPU0_SB_CB<0>
  97  VSS42  POWER  = GND
  98  CB1_B  BI  = M_E_CPU0_SB_CB<1>
  99  VSS43  POWER  = GND
  100  DQ0_B  BI  = M_E_CPU0_SB_DQ<0>
  101  VSS44  POWER  = GND
  102  DQ1_B  BI  = M_E_CPU0_SB_DQ<1>
  103  VSS45  POWER  = GND
  104  DQS0_B_T  BI  = M_E_CPU0_SB_DQS_DP<0>
  105  DQS0_B_C  BI  = M_E_CPU0_SB_DQS_DN<0>
  106  VSS46  POWER  = GND
  107  DQ4_B  BI  = M_E_CPU0_SB_DQ<4>
  108  VSS47  POWER  = GND
  109  DQ5_B  BI  = M_E_CPU0_SB_DQ<5>
  110  VSS48  POWER  = GND
  111  DQ8_B  BI  = M_E_CPU0_SB_DQ<8>
  112  VSS49  POWER  = GND
  113  DQ9_B  BI  = M_E_CPU0_SB_DQ<9>
  114  VSS50  POWER  = GND
  115  DQS1_B_T  BI  = M_E_CPU0_SB_DQS_DP<1>
  116  DQS1_B_C  BI  = M_E_CPU0_SB_DQS_DN<1>
  117  VSS51  POWER  = GND
  118  DQ12_B  BI  = M_E_CPU0_SB_DQ<12>
  119  VSS52  POWER  = GND
  120  DQ13_B  BI  = M_E_CPU0_SB_DQ<13>
  121  VSS53  POWER  = GND
  122  DQ16_B  BI  = M_E_CPU0_SB_DQ<16>
  123  VSS54  POWER  = GND
  124  DQ17_B  BI  = M_E_CPU0_SB_DQ<17>
  125  VSS55  POWER  = GND
  126  DQS2_B_T  BI  = M_E_CPU0_SB_DQS_DP<2>
  127  DQS2_B_C  BI  = M_E_CPU0_SB_DQS_DN<2>
  128  VSS56  POWER  = GND
  129  DQ20_B  BI  = M_E_CPU0_SB_DQ<20>
  130  VSS57  POWER  = GND
  131  DQ21_B  BI  = M_E_CPU0_SB_DQ<21>
  132  VSS58  POWER  = GND
  133  DQ24_B  BI  = M_E_CPU0_SB_DQ<24>
  134  VSS59  POWER  = GND
  135  DQ25_B  BI  = M_E_CPU0_SB_DQ<25>
  136  VSS60  POWER  = GND
  137  DQS3_B_T  BI  = M_E_CPU0_SB_DQS_DP<3>
  138  DQS3_B_C  BI  = M_E_CPU0_SB_DQS_DN<3>
  139  VSS61  POWER  = GND
  140  DQ28_B  BI  = M_E_CPU0_SB_DQ<28>
  141  VSS62  POWER  = GND
  142  DQ29_B  BI  = M_E_CPU0_SB_DQ<29>
  143  VSS63  POWER  = GND
  144  RFU1  TRI  = TP_CHE_CPU0_DIMM2_FRU_1
  145  VIN_BULK1  POWER  = P12V_S3_AUX_CPU0_NVDIMM
  146  VIN_BULK2  POWER  = P12V_S3_AUX_CPU0_NVDIMM
  147  \pwr_good||fail_n\  BI  = PWRGD_CHE_CPU0_DIMM2
  148  HSA  IN  = PD_CHE_CPU0_DIMM2_SAA
  149  RFU2  TRI  = TP_CHE_CPU0_DIMM2_FRU_2
  150  RFU3  TRI  = TP_CHE_CPU0_DIMM2_FRU_3
  151  VSS64  POWER  = GND
  152  DQ2_A  BI  = M_E_CPU0_SA_DQ<2>
  153  VSS65  POWER  = GND
  154  DQ3_A  BI  = M_E_CPU0_SA_DQ<3>
  155  VSS66  POWER  = GND
  156  \dqs5_a_c||tdqs5_a_c||dqs5_a_t||tdqs5_a_t\  BI  = M_E_CPU0_SA_DQS_DN<5>
  157  \dqs5_a_t||tdqs5_a_t\  BI  = M_E_CPU0_SA_DQS_DP<5>
  158  VSS67  POWER  = GND
  159  DQ6_A  BI  = M_E_CPU0_SA_DQ<6>
  160  VSS68  POWER  = GND
  161  DQ7_A  BI  = M_E_CPU0_SA_DQ<7>
  162  VSS69  POWER  = GND
  163  DQ10_A  BI  = M_E_CPU0_SA_DQ<10>
  164  VSS70  POWER  = GND
  165  DQ11_A  BI  = M_E_CPU0_SA_DQ<11>
  166  VSS71  POWER  = GND
  167  \dqs6_a_c||tdqs6_a_c||dqs6_a_t||tdqs6_a_t\  BI  = M_E_CPU0_SA_DQS_DN<6>
  168  \dqs6_a_t||tdqs6_a_t\  BI  = M_E_CPU0_SA_DQS_DP<6>
  169  VSS72  POWER  = GND
  170  DQ14_A  BI  = M_E_CPU0_SA_DQ<14>
  171  VSS73  POWER  = GND
  172  DQ15_A  BI  = M_E_CPU0_SA_DQ<15>
  173  VSS74  POWER  = GND
  174  DQ18_A  BI  = M_E_CPU0_SA_DQ<18>
  175  VSS75  POWER  = GND
  176  DQ19_A  BI  = M_E_CPU0_SA_DQ<19>
  177  VSS76  POWER  = GND
  178  \dqs7_a_c||tdqs7_a_c\  BI  = M_E_CPU0_SA_DQS_DN<7>
  179  \dqs7_a_t||tdqs7_a_t\  BI  = M_E_CPU0_SA_DQS_DP<7>
  180  VSS77  POWER  = GND
  181  DQ22_A  BI  = M_E_CPU0_SA_DQ<22>
  182  VSS78  POWER  = GND
  183  DQ23_A  BI  = M_E_CPU0_SA_DQ<23>
  184  VSS79  POWER  = GND
  185  DQ26_A  BI  = M_E_CPU0_SA_DQ<26>
  186  VSS80  POWER  = GND
  187  DQ27_A  BI  = M_E_CPU0_SA_DQ<27>
  188  VSS81  POWER  = GND
  189  \dqs8_a_c||tdqs8_a_c\  BI  = M_E_CPU0_SA_DQS_DN<8>
  190  \dqs8_a_t||tdqs8_a_t\  BI  = M_E_CPU0_SA_DQS_DP<8>
  191  VSS82  POWER  = GND
  192  DQ30_A  BI  = M_E_CPU0_SA_DQ<30>
  193  VSS83  POWER  = GND
  194  DQ31_A  BI  = M_E_CPU0_SA_DQ<31>
  195  VSS84  POWER  = GND
  196  CB2_A  BI  = M_E_CPU0_SA_CB<2>
  197  VSS85  POWER  = GND
  198  CB3_A  BI  = M_E_CPU0_SA_CB<3>
  199  VSS86  POWER  = GND
  200  \dqs9_a_c||tdqs9_a_c\  BI  = M_E_CPU0_SA_DQS_DN<9>
  201  \dqs9_a_t||tdqs9_a_t\  BI  = M_E_CPU0_SA_DQS_DP<9>
  202  VSS87  POWER  = GND
  203  CB6_A  BI  = M_E_CPU0_SA_CB<6>
  204  VSS88  POWER  = GND
  205  CB7_A  BI  = M_E_CPU0_SA_CB<7>
  206  VSS89  POWER  = GND
  207  RESET_N  IN  = RST_M_EF_CPU0_FPGA_N
  208  VSS90  POWER  = GND
  209  CS1_A_N  IN  = M_E_CPU0_SA_CS_N<3>
  210  VSS91  POWER  = GND
  211  CA1_A  IN  = M_E_CPU0_SA_CA<1>
  212  VSS92  POWER  = GND
  213  CA3_A  IN  = M_E_CPU0_SA_CA<3>
  214  VSS93  POWER  = GND
  215  CA5_A  IN  = M_E_CPU0_SA_CA<5>
  216  VSS94  POWER  = GND
  217  CK_T  IN  = M_E_CPU0_CLK_DP<1>
  218  CK_C  IN  = M_E_CPU0_CLK_DN<1>
  219  VSS95  POWER  = GND
  220  RFU4  TRI  = TP_CHE_CPU0_DIMM2_FRU_4
  221  CA1_B  IN  = M_E_CPU0_SB_CA<1>
  222  VSS96  POWER  = GND
  223  CA3_B  IN  = M_E_CPU0_SB_CA<3>
  224  VSS97  POWER  = GND
  225  CA5_B  IN  = M_E_CPU0_SB_CA<5>
  226  VSS98  POWER  = GND
  227  PAR_B  IN  = M_E_CPU0_SB_PAR
  228  VSS99  POWER  = GND
  229  CS1_B_N  IN  = M_E_CPU0_SB_CS_N<3>
  230  VSS100  POWER  = GND
  231  RFU5  TRI  = TP_CHE_CPU0_DIMM2_FRU_5
  232  RFU6  TRI  = TP_CHE_CPU0_DIMM2_FRU_6
  233  VSS101  POWER  = GND
  234  CB6_B  BI  = M_E_CPU0_SB_CB<6>
  235  VSS102  POWER  = GND
  236  CB7_B  BI  = M_E_CPU0_SB_CB<7>
  237  VSS103  POWER  = GND
  238  DQS4_B_C  BI  = M_E_CPU0_SB_DQS_DN<4>
  239  DQS4_B_T  BI  = M_E_CPU0_SB_DQS_DP<4>
  240  VSS104  POWER  = GND
  241  CB2_B  BI  = M_E_CPU0_SB_CB<2>
  242  VSS105  POWER  = GND
  243  CB3_B  BI  = M_E_CPU0_SB_CB<3>
  244  VSS106  POWER  = GND
  245  DQ2_B  BI  = M_E_CPU0_SB_DQ<2>
  246  VSS107  POWER  = GND
  247  DQ3_B  BI  = M_E_CPU0_SB_DQ<3>
  248  VSS108  POWER  = GND
  249  \dqs5_b_c||tdqs5_b_c\  BI  = M_E_CPU0_SB_DQS_DN<5>
  250  \dqs5_b_t||tdqs5_b_t\  BI  = M_E_CPU0_SB_DQS_DP<5>
  251  VSS109  POWER  = GND
  252  DQ6_B  BI  = M_E_CPU0_SB_DQ<6>
  253  VSS110  POWER  = GND
  254  DQ7_B  BI  = M_E_CPU0_SB_DQ<7>
  255  VSS111  POWER  = GND
  256  DQ10_B  BI  = M_E_CPU0_SB_DQ<10>
  257  VSS112  POWER  = GND
  258  DQ11_B  BI  = M_E_CPU0_SB_DQ<11>
  259  VSS113  POWER  = GND
  260  \dqs6_b_c||tdqs6_b_c\  BI  = M_E_CPU0_SB_DQS_DN<6>
  261  \dqs6_b_t||tdqs6_b_t\  BI  = M_E_CPU0_SB_DQS_DP<6>
  262  VSS114  POWER  = GND
  263  DQ14_B  BI  = M_E_CPU0_SB_DQ<14>
  264  VSS115  POWER  = GND
  265  DQ15_B  BI  = M_E_CPU0_SB_DQ<15>
  266  VSS116  POWER  = GND
  267  DQ18_B  BI  = M_E_CPU0_SB_DQ<18>
  268  VSS117  POWER  = GND
  269  DQ19_B  BI  = M_E_CPU0_SB_DQ<19>
  270  VSS118  POWER  = GND
  271  \dqs7_b_c||tdqs7_b_c\  BI  = M_E_CPU0_SB_DQS_DN<7>
  272  \dqs7_b_t||tdqs7_b_t\  BI  = M_E_CPU0_SB_DQS_DP<7>
  273  VSS119  POWER  = GND
  274  DQ22_B  BI  = M_E_CPU0_SB_DQ<22>
  275  VSS120  POWER  = GND
  276  DQ23_B  BI  = M_E_CPU0_SB_DQ<23>
  277  VSS121  POWER  = GND
  278  DQ26_B  BI  = M_E_CPU0_SB_DQ<26>
  279  VSS122  POWER  = GND
  280  DQ27_B  BI  = M_E_CPU0_SB_DQ<27>
  281  VSS123  POWER  = GND
  282  \dqs8_b_c||tdqs8_b_c\  BI  = M_E_CPU0_SB_DQS_DN<8>
  283  \dqs8_b_t||tdqs8_b_t\  BI  = M_E_CPU0_SB_DQS_DP<8>
  284  VSS124  POWER  = GND
  285  DQ30_B  BI  = M_E_CPU0_SB_DQ<30>
  286  VSS125  POWER  = GND
  287  DQ31_B  BI  = M_E_CPU0_SB_DQ<31>
  288  VSS126  POWER  = GND
  G1  G1  POWER  = GND
  G2  G2  POWER  = GND
  G3  G3  POWER  = GND
